(kicad_pcb
	(version 20260206)
	(generator "pcbnew")
	(generator_version "10.0")
	(general
		(thickness 1.6)
		(legacy_teardrops no)
	)
	(paper "A4")
	(title_block
		(title "03242023_DA0F0TMBIJ0_F0T_Motherboard_J_brd_V01_OCP.brd")
		(comment 1 "Grand Teton / footprints 5836-5841 of 6105")
	)
	(layers
		(0 "F.Cu" signal "TOP")
		(4 "In1.Cu" signal "GND")
		(6 "In2.Cu" signal "IN1")
		(8 "In3.Cu" signal "GND1")
		(10 "In4.Cu" signal "IN2")
		(12 "In5.Cu" signal "GND2")
		(14 "In6.Cu" signal "IN3")
		(16 "In7.Cu" signal "GND3")
		(18 "In8.Cu" signal "VCC")
		(20 "In9.Cu" signal "VCC1")
		(22 "In10.Cu" signal "GND4")
		(24 "In11.Cu" signal "IN4")
		(26 "In12.Cu" signal "GND5")
		(28 "In13.Cu" signal "IN5")
		(30 "In14.Cu" signal "GND6")
		(32 "In15.Cu" signal "IN6")
		(34 "In16.Cu" signal "GND7")
		(2 "B.Cu" signal "BOTTOM")
		(9 "F.Adhes" user "F.Adhesive")
		(11 "B.Adhes" user "B.Adhesive")
		(13 "F.Paste" user "Package Geometry/Pastemask Top")
		(15 "B.Paste" user "Package Geometry/Pastemask Bottom")
		(5 "F.SilkS" user "Ref Des/Silkscreen Top")
		(7 "B.SilkS" user "Ref Des/Silkscreen Bottom")
		(1 "F.Mask" user "Board Geometry/Soldermask Top")
		(3 "B.Mask" user "Board Geometry/Soldermask Bottom")
		(17 "Dwgs.User" user "User.Drawings")
		(19 "Cmts.User" user "User.Comments")
		(21 "Eco1.User" user "User.Eco1")
		(23 "Eco2.User" user "User.Eco2")
		(25 "Edge.Cuts" user "Board Geometry/Outline")
		(27 "Margin" user)
		(31 "F.CrtYd" user "Package Geometry/Place Bound Top")
		(29 "B.CrtYd" user "Package Geometry/Place Bound Bottom")
		(35 "F.Fab" user "Ref Des/Assembly Top")
		(33 "B.Fab" user "Ref Des/Assembly Bottom")
	)
	(footprint ""
		(layer "B.Cu")
		(at 379.720602 -190.795148 90)
		(property "Reference" "R690"
			(at 0 0 90)
			(layer "B.SilkS")
			(hide yes)
			(effects
				(font
					(size 1.27 1.27)
				)
				(justify mirror)
			)
		)
		(property "Value" ""
			(at 0 0 90)
			(layer "B.Fab")
			(effects
				(font
					(size 1.27 1.27)
				)
				(justify mirror)
			)
		)
		(duplicate_pad_numbers_are_jumpers no)
		(fp_line
			(start 0.7874 -0.4064)
			(end -0.7874 -0.4064)
			(stroke
				(width 0.1524)
				(type default)
			)
			(layer "B.SilkS")
		)
		(fp_line
			(start -0.7874 -0.4064)
			(end -0.7874 0.4064)
			(stroke
				(width 0.1524)
				(type default)
			)
			(layer "B.SilkS")
		)
		(fp_line
			(start 0.7874 0.4064)
			(end 0.7874 -0.4064)
			(stroke
				(width 0.1524)
				(type default)
			)
			(layer "B.SilkS")
		)
		(fp_line
			(start -0.7874 0.4064)
			(end 0.7874 0.4064)
			(stroke
				(width 0.1524)
				(type default)
			)
			(layer "B.SilkS")
		)
		(fp_line
			(start 0.67945 -0.305054)
			(end 0.12065 -0.305054)
			(stroke
				(width 0.1)
				(type default)
			)
			(layer "B.Fab")
		)
		(fp_line
			(start 0.12065 -0.305054)
			(end 0.12065 -0.2794)
			(stroke
				(width 0.1)
				(type default)
			)
			(layer "B.Fab")
		)
		(fp_line
			(start -0.12065 -0.3048)
			(end -0.67945 -0.3048)
			(stroke
				(width 0.1)
				(type default)
			)
			(layer "B.Fab")
		)
		(fp_line
			(start -0.67945 -0.3048)
			(end -0.67945 0.3048)
			(stroke
				(width 0.1)
				(type default)
			)
			(layer "B.Fab")
		)
		(fp_line
			(start 0.12065 -0.2794)
			(end -0.12065 -0.2794)
			(stroke
				(width 0.1)
				(type default)
			)
			(layer "B.Fab")
		)
		(fp_line
			(start -0.12065 -0.2794)
			(end -0.12065 -0.3048)
			(stroke
				(width 0.1)
				(type default)
			)
			(layer "B.Fab")
		)
		(fp_line
			(start 0.12065 0.2794)
			(end 0.12065 0.3048)
			(stroke
				(width 0.1)
				(type default)
			)
			(layer "B.Fab")
		)
		(fp_line
			(start -0.120396 0.2794)
			(end 0.12065 0.2794)
			(stroke
				(width 0.1)
				(type default)
			)
			(layer "B.Fab")
		)
		(fp_line
			(start 0.67945 0.3048)
			(end 0.67945 -0.305054)
			(stroke
				(width 0.1)
				(type default)
			)
			(layer "B.Fab")
		)
		(fp_line
			(start 0.12065 0.3048)
			(end 0.67945 0.3048)
			(stroke
				(width 0.1)
				(type default)
			)
			(layer "B.Fab")
		)
		(fp_line
			(start -0.120396 0.3048)
			(end -0.120396 0.2794)
			(stroke
				(width 0.1)
				(type default)
			)
			(layer "B.Fab")
		)
		(fp_line
			(start -0.67945 0.3048)
			(end -0.120396 0.3048)
			(stroke
				(width 0.1)
				(type default)
			)
			(layer "B.Fab")
		)
		(pad "1" smd circle
			(at 0.40005 0 270)
			(size 0 0)
			(layers "B.Cu" "B.Mask" "B.Paste")
			(net "I3C_SPD_DDREFGH_CPU0_SDA")
		)
		(pad "2" smd circle
			(at -0.40005 0 270)
			(size 0 0)
			(layers "B.Cu" "B.Mask" "B.Paste")
			(net "I3C_SPD_DDREFGH_CPU0_R_SDA")
		)
	)
	(footprint ""
		(layer "B.Cu")
		(at 197.182232 -123.139708 180)
		(property "Reference" "R4521"
			(at 0 0 0)
			(layer "B.SilkS")
			(hide yes)
			(effects
				(font
					(size 1.27 1.27)
				)
				(justify mirror)
			)
		)
		(property "Value" ""
			(at 0 0 0)
			(layer "B.Fab")
			(effects
				(font
					(size 1.27 1.27)
				)
				(justify mirror)
			)
		)
		(duplicate_pad_numbers_are_jumpers no)
		(fp_line
			(start 0.7874 0.4064)
			(end 0.7874 -0.4064)
			(stroke
				(width 0.1524)
				(type default)
			)
			(layer "B.SilkS")
		)
		(fp_line
			(start 0.7874 -0.4064)
			(end -0.7874 -0.4064)
			(stroke
				(width 0.1524)
				(type default)
			)
			(layer "B.SilkS")
		)
		(fp_line
			(start -0.7874 0.4064)
			(end 0.7874 0.4064)
			(stroke
				(width 0.1524)
				(type default)
			)
			(layer "B.SilkS")
		)
		(fp_line
			(start -0.7874 -0.4064)
			(end -0.7874 0.4064)
			(stroke
				(width 0.1524)
				(type default)
			)
			(layer "B.SilkS")
		)
		(fp_line
			(start 0.67945 0.3048)
			(end 0.67945 -0.305054)
			(stroke
				(width 0.1)
				(type default)
			)
			(layer "B.Fab")
		)
		(fp_line
			(start 0.67945 -0.305054)
			(end 0.12065 -0.305054)
			(stroke
				(width 0.1)
				(type default)
			)
			(layer "B.Fab")
		)
		(fp_line
			(start 0.12065 0.3048)
			(end 0.67945 0.3048)
			(stroke
				(width 0.1)
				(type default)
			)
			(layer "B.Fab")
		)
		(fp_line
			(start 0.12065 0.2794)
			(end 0.12065 0.3048)
			(stroke
				(width 0.1)
				(type default)
			)
			(layer "B.Fab")
		)
		(fp_line
			(start 0.12065 -0.2794)
			(end -0.12065 -0.2794)
			(stroke
				(width 0.1)
				(type default)
			)
			(layer "B.Fab")
		)
		(fp_line
			(start 0.12065 -0.305054)
			(end 0.12065 -0.2794)
			(stroke
				(width 0.1)
				(type default)
			)
			(layer "B.Fab")
		)
		(fp_line
			(start -0.120396 0.3048)
			(end -0.120396 0.2794)
			(stroke
				(width 0.1)
				(type default)
			)
			(layer "B.Fab")
		)
		(fp_line
			(start -0.120396 0.2794)
			(end 0.12065 0.2794)
			(stroke
				(width 0.1)
				(type default)
			)
			(layer "B.Fab")
		)
		(fp_line
			(start -0.12065 -0.2794)
			(end -0.12065 -0.3048)
			(stroke
				(width 0.1)
				(type default)
			)
			(layer "B.Fab")
		)
		(fp_line
			(start -0.12065 -0.3048)
			(end -0.67945 -0.3048)
			(stroke
				(width 0.1)
				(type default)
			)
			(layer "B.Fab")
		)
		(fp_line
			(start -0.67945 0.3048)
			(end -0.120396 0.3048)
			(stroke
				(width 0.1)
				(type default)
			)
			(layer "B.Fab")
		)
		(fp_line
			(start -0.67945 -0.3048)
			(end -0.67945 0.3048)
			(stroke
				(width 0.1)
				(type default)
			)
			(layer "B.Fab")
		)
		(pad "1" smd circle
			(at 0.40005 0)
			(size 0 0)
			(layers "B.Cu" "B.Mask" "B.Paste")
			(net "P3V3_AUX")
		)
		(pad "2" smd circle
			(at -0.40005 0)
			(size 0 0)
			(layers "B.Cu" "B.Mask" "B.Paste")
			(net "CLK_GEN2_BMC_RC_OE_N")
		)
	)
	(footprint ""
		(layer "B.Cu")
		(at 366.310418 -296.054526)
		(property "Reference" "C396"
			(at 0 0 0)
			(layer "B.SilkS")
			(hide yes)
			(effects
				(font
					(size 1.27 1.27)
				)
				(justify mirror)
			)
		)
		(property "Value" ""
			(at 0 0 0)
			(layer "B.Fab")
			(effects
				(font
					(size 1.27 1.27)
				)
				(justify mirror)
			)
		)
		(duplicate_pad_numbers_are_jumpers no)
		(fp_line
			(start -1.524 -0.762)
			(end -1.524 0.762)
			(stroke
				(width 0.1524)
				(type default)
			)
			(layer "B.SilkS")
		)
		(fp_line
			(start -1.524 0.762)
			(end 1.524 0.762)
			(stroke
				(width 0.1524)
				(type default)
			)
			(layer "B.SilkS")
		)
		(fp_line
			(start 1.524 -0.762)
			(end -1.524 -0.762)
			(stroke
				(width 0.1524)
				(type default)
			)
			(layer "B.SilkS")
		)
		(fp_line
			(start 1.524 0.762)
			(end 1.524 -0.762)
			(stroke
				(width 0.1524)
				(type default)
			)
			(layer "B.SilkS")
		)
		(fp_line
			(start -1.1049 -0.724916)
			(end 1.1049 -0.724916)
			(stroke
				(width 0.1)
				(type default)
			)
			(layer "B.Fab")
		)
		(fp_line
			(start -1.1049 0.724916)
			(end -1.1049 -0.724916)
			(stroke
				(width 0.1)
				(type default)
			)
			(layer "B.Fab")
		)
		(fp_line
			(start 1.1049 -0.724916)
			(end 1.1049 0.724916)
			(stroke
				(width 0.1)
				(type default)
			)
			(layer "B.Fab")
		)
		(fp_line
			(start 1.1049 0.724916)
			(end -1.1049 0.724916)
			(stroke
				(width 0.1)
				(type default)
			)
			(layer "B.Fab")
		)
		(pad "1" smd rect
			(at 0.889 0)
			(size 1.016 1.27)
			(layers "B.Cu" "B.Mask" "B.Paste")
			(net "PVCCIN_CPU0")
		)
		(pad "2" smd rect
			(at -0.889 0)
			(size 1.016 1.27)
			(layers "B.Cu" "B.Mask" "B.Paste")
			(net "GND")
		)
	)
	(footprint ""
		(layer "B.Cu")
		(at 325.322438 -188.45911 -90)
		(property "Reference" "R5"
			(at 0 0 90)
			(layer "B.SilkS")
			(hide yes)
			(effects
				(font
					(size 1.27 1.27)
				)
				(justify mirror)
			)
		)
		(property "Value" ""
			(at 0 0 90)
			(layer "B.Fab")
			(effects
				(font
					(size 1.27 1.27)
				)
				(justify mirror)
			)
		)
		(duplicate_pad_numbers_are_jumpers no)
		(fp_line
			(start -0.7874 0.4064)
			(end 0.7874 0.4064)
			(stroke
				(width 0.1524)
				(type default)
			)
			(layer "B.SilkS")
		)
		(fp_line
			(start 0.7874 0.4064)
			(end 0.7874 -0.4064)
			(stroke
				(width 0.1524)
				(type default)
			)
			(layer "B.SilkS")
		)
		(fp_line
			(start -0.7874 -0.4064)
			(end -0.7874 0.4064)
			(stroke
				(width 0.1524)
				(type default)
			)
			(layer "B.SilkS")
		)
		(fp_line
			(start 0.7874 -0.4064)
			(end -0.7874 -0.4064)
			(stroke
				(width 0.1524)
				(type default)
			)
			(layer "B.SilkS")
		)
		(fp_line
			(start -0.67945 0.3048)
			(end -0.120396 0.3048)
			(stroke
				(width 0.1)
				(type default)
			)
			(layer "B.Fab")
		)
		(fp_line
			(start -0.120396 0.3048)
			(end -0.120396 0.2794)
			(stroke
				(width 0.1)
				(type default)
			)
			(layer "B.Fab")
		)
		(fp_line
			(start 0.12065 0.3048)
			(end 0.67945 0.3048)
			(stroke
				(width 0.1)
				(type default)
			)
			(layer "B.Fab")
		)
		(fp_line
			(start 0.67945 0.3048)
			(end 0.67945 -0.305054)
			(stroke
				(width 0.1)
				(type default)
			)
			(layer "B.Fab")
		)
		(fp_line
			(start -0.120396 0.2794)
			(end 0.12065 0.2794)
			(stroke
				(width 0.1)
				(type default)
			)
			(layer "B.Fab")
		)
		(fp_line
			(start 0.12065 0.2794)
			(end 0.12065 0.3048)
			(stroke
				(width 0.1)
				(type default)
			)
			(layer "B.Fab")
		)
		(fp_line
			(start -0.12065 -0.2794)
			(end -0.12065 -0.3048)
			(stroke
				(width 0.1)
				(type default)
			)
			(layer "B.Fab")
		)
		(fp_line
			(start 0.12065 -0.2794)
			(end -0.12065 -0.2794)
			(stroke
				(width 0.1)
				(type default)
			)
			(layer "B.Fab")
		)
		(fp_line
			(start -0.67945 -0.3048)
			(end -0.67945 0.3048)
			(stroke
				(width 0.1)
				(type default)
			)
			(layer "B.Fab")
		)
		(fp_line
			(start -0.12065 -0.3048)
			(end -0.67945 -0.3048)
			(stroke
				(width 0.1)
				(type default)
			)
			(layer "B.Fab")
		)
		(fp_line
			(start 0.12065 -0.305054)
			(end 0.12065 -0.2794)
			(stroke
				(width 0.1)
				(type default)
			)
			(layer "B.Fab")
		)
		(fp_line
			(start 0.67945 -0.305054)
			(end 0.12065 -0.305054)
			(stroke
				(width 0.1)
				(type default)
			)
			(layer "B.Fab")
		)
		(pad "1" smd circle
			(at 0.40005 0 90)
			(size 0 0)
			(layers "B.Cu" "B.Mask" "B.Paste")
			(net "JTAG_DBP_CPU_GTL_TCK")
		)
		(pad "2" smd circle
			(at -0.40005 0 90)
			(size 0 0)
			(layers "B.Cu" "B.Mask" "B.Paste")
			(net "JTAG_DBP_CPU0_GTL_R_TCK")
		)
	)
	(footprint ""
		(layer "B.Cu")
		(at 168.742868 -197.131178 -90)
		(property "Reference" "R4301"
			(at 0 0 90)
			(layer "B.SilkS")
			(hide yes)
			(effects
				(font
					(size 1.27 1.27)
				)
				(justify mirror)
			)
		)
		(property "Value" ""
			(at 0 0 90)
			(layer "B.Fab")
			(effects
				(font
					(size 1.27 1.27)
				)
				(justify mirror)
			)
		)
		(duplicate_pad_numbers_are_jumpers no)
		(fp_line
			(start -0.7874 0.4064)
			(end 0.7874 0.4064)
			(stroke
				(width 0.1524)
				(type default)
			)
			(layer "B.SilkS")
		)
		(fp_line
			(start 0.7874 0.4064)
			(end 0.7874 -0.4064)
			(stroke
				(width 0.1524)
				(type default)
			)
			(layer "B.SilkS")
		)
		(fp_line
			(start -0.7874 -0.4064)
			(end -0.7874 0.4064)
			(stroke
				(width 0.1524)
				(type default)
			)
			(layer "B.SilkS")
		)
		(fp_line
			(start 0.7874 -0.4064)
			(end -0.7874 -0.4064)
			(stroke
				(width 0.1524)
				(type default)
			)
			(layer "B.SilkS")
		)
		(fp_line
			(start -0.67945 0.3048)
			(end -0.120396 0.3048)
			(stroke
				(width 0.1)
				(type default)
			)
			(layer "B.Fab")
		)
		(fp_line
			(start -0.120396 0.3048)
			(end -0.120396 0.2794)
			(stroke
				(width 0.1)
				(type default)
			)
			(layer "B.Fab")
		)
		(fp_line
			(start 0.12065 0.3048)
			(end 0.67945 0.3048)
			(stroke
				(width 0.1)
				(type default)
			)
			(layer "B.Fab")
		)
		(fp_line
			(start 0.67945 0.3048)
			(end 0.67945 -0.305054)
			(stroke
				(width 0.1)
				(type default)
			)
			(layer "B.Fab")
		)
		(fp_line
			(start -0.120396 0.2794)
			(end 0.12065 0.2794)
			(stroke
				(width 0.1)
				(type default)
			)
			(layer "B.Fab")
		)
		(fp_line
			(start 0.12065 0.2794)
			(end 0.12065 0.3048)
			(stroke
				(width 0.1)
				(type default)
			)
			(layer "B.Fab")
		)
		(fp_line
			(start -0.12065 -0.2794)
			(end -0.12065 -0.3048)
			(stroke
				(width 0.1)
				(type default)
			)
			(layer "B.Fab")
		)
		(fp_line
			(start 0.12065 -0.2794)
			(end -0.12065 -0.2794)
			(stroke
				(width 0.1)
				(type default)
			)
			(layer "B.Fab")
		)
		(fp_line
			(start -0.67945 -0.3048)
			(end -0.67945 0.3048)
			(stroke
				(width 0.1)
				(type default)
			)
			(layer "B.Fab")
		)
		(fp_line
			(start -0.12065 -0.3048)
			(end -0.67945 -0.3048)
			(stroke
				(width 0.1)
				(type default)
			)
			(layer "B.Fab")
		)
		(fp_line
			(start 0.12065 -0.305054)
			(end 0.12065 -0.2794)
			(stroke
				(width 0.1)
				(type default)
			)
			(layer "B.Fab")
		)
		(fp_line
			(start 0.67945 -0.305054)
			(end 0.12065 -0.305054)
			(stroke
				(width 0.1)
				(type default)
			)
			(layer "B.Fab")
		)
		(pad "1" smd circle
			(at 0.40005 0 90)
			(size 0 0)
			(layers "B.Cu" "B.Mask" "B.Paste")
			(net "PWRGD_DRAMPWRGD_CPU1_EF_LVC1_R2")
		)
		(pad "2" smd circle
			(at -0.40005 0 90)
			(size 0 0)
			(layers "B.Cu" "B.Mask" "B.Paste")
			(net "PWRGD_DRAMPWRGD_CPU1_EF_LVC1_R")
		)
	)
	(footprint ""
		(layer "B.Cu")
		(at 440.617356 -318.933576 90)
		(property "Reference" "R890"
			(at 0 0 90)
			(layer "B.SilkS")
			(hide yes)
			(effects
				(font
					(size 1.27 1.27)
				)
				(justify mirror)
			)
		)
		(property "Value" ""
			(at 0 0 90)
			(layer "B.Fab")
			(effects
				(font
					(size 1.27 1.27)
				)
				(justify mirror)
			)
		)
		(duplicate_pad_numbers_are_jumpers no)
		(fp_line
			(start 0.7874 -0.4064)
			(end -0.7874 -0.4064)
			(stroke
				(width 0.1524)
				(type default)
			)
			(layer "B.SilkS")
		)
		(fp_line
			(start -0.7874 -0.4064)
			(end -0.7874 0.4064)
			(stroke
				(width 0.1524)
				(type default)
			)
			(layer "B.SilkS")
		)
		(fp_line
			(start 0.7874 0.4064)
			(end 0.7874 -0.4064)
			(stroke
				(width 0.1524)
				(type default)
			)
			(layer "B.SilkS")
		)
		(fp_line
			(start -0.7874 0.4064)
			(end 0.7874 0.4064)
			(stroke
				(width 0.1524)
				(type default)
			)
			(layer "B.SilkS")
		)
		(fp_line
			(start 0.67945 -0.305054)
			(end 0.12065 -0.305054)
			(stroke
				(width 0.1)
				(type default)
			)
			(layer "B.Fab")
		)
		(fp_line
			(start 0.12065 -0.305054)
			(end 0.12065 -0.2794)
			(stroke
				(width 0.1)
				(type default)
			)
			(layer "B.Fab")
		)
		(fp_line
			(start -0.12065 -0.3048)
			(end -0.67945 -0.3048)
			(stroke
				(width 0.1)
				(type default)
			)
			(layer "B.Fab")
		)
		(fp_line
			(start -0.67945 -0.3048)
			(end -0.67945 0.3048)
			(stroke
				(width 0.1)
				(type default)
			)
			(layer "B.Fab")
		)
		(fp_line
			(start 0.12065 -0.2794)
			(end -0.12065 -0.2794)
			(stroke
				(width 0.1)
				(type default)
			)
			(layer "B.Fab")
		)
		(fp_line
			(start -0.12065 -0.2794)
			(end -0.12065 -0.3048)
			(stroke
				(width 0.1)
				(type default)
			)
			(layer "B.Fab")
		)
		(fp_line
			(start 0.12065 0.2794)
			(end 0.12065 0.3048)
			(stroke
				(width 0.1)
				(type default)
			)
			(layer "B.Fab")
		)
		(fp_line
			(start -0.120396 0.2794)
			(end 0.12065 0.2794)
			(stroke
				(width 0.1)
				(type default)
			)
			(layer "B.Fab")
		)
		(fp_line
			(start 0.67945 0.3048)
			(end 0.67945 -0.305054)
			(stroke
				(width 0.1)
				(type default)
			)
			(layer "B.Fab")
		)
		(fp_line
			(start 0.12065 0.3048)
			(end 0.67945 0.3048)
			(stroke
				(width 0.1)
				(type default)
			)
			(layer "B.Fab")
		)
		(fp_line
			(start -0.120396 0.3048)
			(end -0.120396 0.2794)
			(stroke
				(width 0.1)
				(type default)
			)
			(layer "B.Fab")
		)
		(fp_line
			(start -0.67945 0.3048)
			(end -0.120396 0.3048)
			(stroke
				(width 0.1)
				(type default)
			)
			(layer "B.Fab")
		)
		(pad "1" smd circle
			(at 0.40005 0 270)
			(size 0 0)
			(layers "B.Cu" "B.Mask" "B.Paste")
			(net "PWRGD_CHG_CPU0_DIMM2")
		)
		(pad "2" smd circle
			(at -0.40005 0 270)
			(size 0 0)
			(layers "B.Cu" "B.Mask" "B.Paste")
			(net "PWRGD_FAIL_CPU0_GH")
		)
	)
)
